# S9S_MB_2U (Grand Teton) — schematic netlist excerpt (pin names and nets, part order shuffled) for the footprints in the layout excerpt that follows; sources: Cadence DE-HDL packaged netlist, KiCad conversion of 03242023_DA0F0TMBIJ0_F0T_Motherboard_J_brd_V01_OCP.brd

R2501  Q_RES  33.2 1% CHIP  pkg 0402LF  page 115 : A = PWRGD_FAIL_CPU0_GH_R1 ; B = PWRGD_FAIL_CPU0_GH_R

(kicad_pcb
	(version 20260206)
	(generator "pcbnew")
	(generator_version "10.0")
	(general
		(thickness 1.6)
		(legacy_teardrops no)
	)
	(paper "A4")
	(title_block
		(title "03242023_DA0F0TMBIJ0_F0T_Motherboard_J_brd_V01_OCP.brd")
		(comment 1 "Grand Teton / footprints 4483-4483 of 6105")
	)
	(layers
		(0 "F.Cu" signal "TOP")
		(4 "In1.Cu" signal "GND")
		(6 "In2.Cu" signal "IN1")
		(8 "In3.Cu" signal "GND1")
		(10 "In4.Cu" signal "IN2")
		(12 "In5.Cu" signal "GND2")
		(14 "In6.Cu" signal "IN3")
		(16 "In7.Cu" signal "GND3")
		(18 "In8.Cu" signal "VCC")
		(20 "In9.Cu" signal "VCC1")
		(22 "In10.Cu" signal "GND4")
		(24 "In11.Cu" signal "IN4")
		(26 "In12.Cu" signal "GND5")
		(28 "In13.Cu" signal "IN5")
		(30 "In14.Cu" signal "GND6")
		(32 "In15.Cu" signal "IN6")
		(34 "In16.Cu" signal "GND7")
		(2 "B.Cu" signal "BOTTOM")
		(9 "F.Adhes" user "F.Adhesive")
		(11 "B.Adhes" user "B.Adhesive")
		(13 "F.Paste" user "Package Geometry/Pastemask Top")
		(15 "B.Paste" user "Package Geometry/Pastemask Bottom")
		(5 "F.SilkS" user "Ref Des/Silkscreen Top")
		(7 "B.SilkS" user "Ref Des/Silkscreen Bottom")
		(1 "F.Mask" user "Board Geometry/Soldermask Top")
		(3 "B.Mask" user "Board Geometry/Soldermask Bottom")
		(17 "Dwgs.User" user "User.Drawings")
		(19 "Cmts.User" user "User.Comments")
		(21 "Eco1.User" user "User.Eco1")
		(23 "Eco2.User" user "User.Eco2")
		(25 "Edge.Cuts" user "Board Geometry/Outline")
		(27 "Margin" user)
		(31 "F.CrtYd" user "Package Geometry/Place Bound Top")
		(29 "B.CrtYd" user "Package Geometry/Place Bound Bottom")
		(35 "F.Fab" user "Ref Des/Assembly Top")
		(33 "B.Fab" user "Ref Des/Assembly Bottom")
	)
	(footprint ""
		(layer "B.Cu")
		(at 456.543918 -314.80506 90)
		(property "Reference" "R2501"
			(at 0 0 90)
			(layer "B.SilkS")
			(hide yes)
			(effects
				(font
					(size 1.27 1.27)
				)
				(justify mirror)
			)
		)
		(property "Value" ""
			(at 0 0 90)
			(layer "B.Fab")
			(effects
				(font
					(size 1.27 1.27)
				)
				(justify mirror)
			)
		)
		(duplicate_pad_numbers_are_jumpers no)
		(fp_line
			(start 0.7874 -0.4064)
			(end -0.7874 -0.4064)
			(stroke
				(width 0.1524)
				(type default)
			)
			(layer "B.SilkS")
		)
		(fp_line
			(start -0.7874 -0.4064)
			(end -0.7874 0.4064)
			(stroke
				(width 0.1524)
				(type default)
			)
			(layer "B.SilkS")
		)
		(fp_line
			(start 0.7874 0.4064)
			(end 0.7874 -0.4064)
			(stroke
				(width 0.1524)
				(type default)
			)
			(layer "B.SilkS")
		)
		(fp_line
			(start -0.7874 0.4064)
			(end 0.7874 0.4064)
			(stroke
				(width 0.1524)
				(type default)
			)
			(layer "B.SilkS")
		)
		(fp_line
			(start 0.67945 -0.305054)
			(end 0.12065 -0.305054)
			(stroke
				(width 0.1)
				(type default)
			)
			(layer "B.Fab")
		)
		(fp_line
			(start 0.12065 -0.305054)
			(end 0.12065 -0.2794)
			(stroke
				(width 0.1)
				(type default)
			)
			(layer "B.Fab")
		)
		(fp_line
			(start -0.12065 -0.3048)
			(end -0.67945 -0.3048)
			(stroke
				(width 0.1)
				(type default)
			)
			(layer "B.Fab")
		)
		(fp_line
			(start -0.67945 -0.3048)
			(end -0.67945 0.3048)
			(stroke
				(width 0.1)
				(type default)
			)
			(layer "B.Fab")
		)
		(fp_line
			(start 0.12065 -0.2794)
			(end -0.12065 -0.2794)
			(stroke
				(width 0.1)
				(type default)
			)
			(layer "B.Fab")
		)
		(fp_line
			(start -0.12065 -0.2794)
			(end -0.12065 -0.3048)
			(stroke
				(width 0.1)
				(type default)
			)
			(layer "B.Fab")
		)
		(fp_line
			(start 0.12065 0.2794)
			(end 0.12065 0.3048)
			(stroke
				(width 0.1)
				(type default)
			)
			(layer "B.Fab")
		)
		(fp_line
			(start -0.120396 0.2794)
			(end 0.12065 0.2794)
			(stroke
				(width 0.1)
				(type default)
			)
			(layer "B.Fab")
		)
		(fp_line
			(start 0.67945 0.3048)
			(end 0.67945 -0.305054)
			(stroke
				(width 0.1)
				(type default)
			)
			(layer "B.Fab")
		)
		(fp_line
			(start 0.12065 0.3048)
			(end 0.67945 0.3048)
			(stroke
				(width 0.1)
				(type default)
			)
			(layer "B.Fab")
		)
		(fp_line
			(start -0.120396 0.3048)
			(end -0.120396 0.2794)
			(stroke
				(width 0.1)
				(type default)
			)
			(layer "B.Fab")
		)
		(fp_line
			(start -0.67945 0.3048)
			(end -0.120396 0.3048)
			(stroke
				(width 0.1)
				(type default)
			)
			(layer "B.Fab")
		)
		(pad "1" smd circle
			(at 0.40005 0 270)
			(size 0 0)
			(layers "B.Cu" "B.Mask" "B.Paste")
			(net "PWRGD_FAIL_CPU0_GH_R1")
		)
		(pad "2" smd circle
			(at -0.40005 0 270)
			(size 0 0)
			(layers "B.Cu" "B.Mask" "B.Paste")
			(net "PWRGD_FAIL_CPU0_GH_R")
		)
	)
)
